# SCM (Grand Teton) — schematic netlist excerpt (pin names and nets, part order shuffled) for the footprints in the layout excerpt that follows; sources: Cadence DE-HDL packaged netlist, KiCad conversion of 12092022_DA0F0TMDCD0_F0T_Management_Board_D_brd_V3_OCP.brd

R178  Q_RES  33.2 1% CHIP  pkg 0402LF  page 13 : A = SPI_BMC_CLK_R ; B = SPI_BMC_BOOT_CLK

(kicad_pcb
	(version 20260206)
	(generator "pcbnew")
	(generator_version "10.0")
	(general
		(thickness 1.6)
		(legacy_teardrops no)
	)
	(paper "A4")
	(title_block
		(title "12092022_DA0F0TMDCD0_F0T_Management_Board_D_brd_V3_OCP.brd")
		(comment 1 "Grand Teton / footprints 440-440 of 1440")
	)
	(layers
		(0 "F.Cu" signal "TOP")
		(4 "In1.Cu" signal "GND")
		(6 "In2.Cu" signal "IN1")
		(8 "In3.Cu" signal "GND1")
		(10 "In4.Cu" signal "IN2")
		(12 "In5.Cu" signal "VCC")
		(14 "In6.Cu" signal "VCC1")
		(16 "In7.Cu" signal "IN3")
		(18 "In8.Cu" signal "GND2")
		(20 "In9.Cu" signal "IN4")
		(22 "In10.Cu" signal "GND3")
		(2 "B.Cu" signal "BOTTOM")
		(9 "F.Adhes" user "F.Adhesive")
		(11 "B.Adhes" user "B.Adhesive")
		(13 "F.Paste" user "Package Geometry/Pastemask Top")
		(15 "B.Paste" user "Package Geometry/Pastemask Bottom")
		(5 "F.SilkS" user "Ref Des/Silkscreen Top")
		(7 "B.SilkS" user "Ref Des/Silkscreen Bottom")
		(1 "F.Mask" user "Board Geometry/Soldermask Top")
		(3 "B.Mask" user "Board Geometry/Soldermask Bottom")
		(17 "Dwgs.User" user "User.Drawings")
		(19 "Cmts.User" user "User.Comments")
		(21 "Eco1.User" user "User.Eco1")
		(23 "Eco2.User" user "User.Eco2")
		(25 "Edge.Cuts" user "Board Geometry/Outline")
		(27 "Margin" user)
		(31 "F.CrtYd" user "Package Geometry/Place Bound Top")
		(29 "B.CrtYd" user "Package Geometry/Place Bound Bottom")
		(35 "F.Fab" user "Ref Des/Assembly Top")
		(33 "B.Fab" user "Ref Des/Assembly Bottom")
	)
	(footprint ""
		(layer "F.Cu")
		(at 52.809648 -63.912496 90)
		(property "Reference" "R178"
			(at 0 0 90)
			(layer "F.SilkS")
			(hide yes)
			(effects
				(font
					(size 1.27 1.27)
				)
			)
		)
		(property "Value" ""
			(at 0 0 90)
			(layer "F.Fab")
			(effects
				(font
					(size 1.27 1.27)
				)
			)
		)
		(duplicate_pad_numbers_are_jumpers no)
		(fp_line
			(start 0.7874 -0.4064)
			(end 0.7874 0.4064)
			(stroke
				(width 0.1524)
				(type default)
			)
			(layer "F.SilkS")
		)
		(fp_line
			(start -0.7874 -0.4064)
			(end 0.7874 -0.4064)
			(stroke
				(width 0.1524)
				(type default)
			)
			(layer "F.SilkS")
		)
		(fp_line
			(start 0.7874 0.4064)
			(end -0.7874 0.4064)
			(stroke
				(width 0.1524)
				(type default)
			)
			(layer "F.SilkS")
		)
		(fp_line
			(start -0.7874 0.4064)
			(end -0.7874 -0.4064)
			(stroke
				(width 0.1524)
				(type default)
			)
			(layer "F.SilkS")
		)
		(fp_line
			(start -0.12065 -0.305054)
			(end -0.12065 -0.2794)
			(stroke
				(width 0.1)
				(type default)
			)
			(layer "F.Fab")
		)
		(fp_line
			(start -0.67945 -0.305054)
			(end -0.12065 -0.305054)
			(stroke
				(width 0.1)
				(type default)
			)
			(layer "F.Fab")
		)
		(fp_line
			(start 0.67945 -0.3048)
			(end 0.67945 0.3048)
			(stroke
				(width 0.1)
				(type default)
			)
			(layer "F.Fab")
		)
		(fp_line
			(start 0.12065 -0.3048)
			(end 0.67945 -0.3048)
			(stroke
				(width 0.1)
				(type default)
			)
			(layer "F.Fab")
		)
		(fp_line
			(start 0.12065 -0.2794)
			(end 0.12065 -0.3048)
			(stroke
				(width 0.1)
				(type default)
			)
			(layer "F.Fab")
		)
		(fp_line
			(start -0.12065 -0.2794)
			(end 0.12065 -0.2794)
			(stroke
				(width 0.1)
				(type default)
			)
			(layer "F.Fab")
		)
		(fp_line
			(start 0.120396 0.2794)
			(end -0.12065 0.2794)
			(stroke
				(width 0.1)
				(type default)
			)
			(layer "F.Fab")
		)
		(fp_line
			(start -0.12065 0.2794)
			(end -0.12065 0.3048)
			(stroke
				(width 0.1)
				(type default)
			)
			(layer "F.Fab")
		)
		(fp_line
			(start 0.67945 0.3048)
			(end 0.120396 0.3048)
			(stroke
				(width 0.1)
				(type default)
			)
			(layer "F.Fab")
		)
		(fp_line
			(start 0.120396 0.3048)
			(end 0.120396 0.2794)
			(stroke
				(width 0.1)
				(type default)
			)
			(layer "F.Fab")
		)
		(fp_line
			(start -0.12065 0.3048)
			(end -0.67945 0.3048)
			(stroke
				(width 0.1)
				(type default)
			)
			(layer "F.Fab")
		)
		(fp_line
			(start -0.67945 0.3048)
			(end -0.67945 -0.305054)
			(stroke
				(width 0.1)
				(type default)
			)
			(layer "F.Fab")
		)
		(pad "1" smd circle
			(at -0.40005 0 90)
			(size 0 0)
			(layers "F.Cu" "F.Mask" "F.Paste")
			(net "SPI_BMC_CLK_R")
		)
		(pad "2" smd circle
			(at 0.40005 0 90)
			(size 0 0)
			(layers "F.Cu" "F.Mask" "F.Paste")
			(net "SPI_BMC_BOOT_CLK")
		)
	)
)
